(kicad_pcb
	(version 20241229)
	(generator "pcbnew")
	(generator_version "9.0")
	(general
		(thickness 1.294)
		(legacy_teardrops no)
	)
	(paper "A3")
	(title_block
		(title "Kintex 410T devboard")
		(date "2024-04-03")
		(rev "1.1.2")
		(comment 9 "footprints 969-974 of 975")
	)
	(layers
		(0 "F.Cu" mixed)
		(4 "In1.Cu" power)
		(6 "In2.Cu" power)
		(8 "In3.Cu" mixed)
		(10 "In4.Cu" power)
		(12 "In5.Cu" mixed)
		(14 "In6.Cu" power)
		(16 "In7.Cu" mixed)
		(18 "In8.Cu" power)
		(2 "B.Cu" mixed)
		(9 "F.Adhes" user "F.Adhesive")
		(11 "B.Adhes" user "B.Adhesive")
		(13 "F.Paste" user)
		(15 "B.Paste" user)
		(5 "F.SilkS" user "F.Silkscreen")
		(7 "B.SilkS" user "B.Silkscreen")
		(1 "F.Mask" user)
		(3 "B.Mask" user)
		(17 "Dwgs.User" user "User.Drawings")
		(19 "Cmts.User" user "User.Comments")
		(21 "Eco1.User" user "User.Eco1")
		(23 "Eco2.User" user "User.Eco2")
		(25 "Edge.Cuts" user)
		(27 "Margin" user)
		(31 "F.CrtYd" user "F.Courtyard")
		(29 "B.CrtYd" user "B.Courtyard")
		(35 "F.Fab" user)
		(33 "B.Fab" user)
	)
	(footprint "antmicro-footprints:C_0402_1005Metric"
		(layer "B.Cu")
		(at 195.68 144.6 -45)
		(descr "Capacitor SMD 0402")
		(tags "capacitor SMD 0402")
		(property "Reference" "C84"
			(at 1.145513 1.223295 315)
			(unlocked yes)
			(layer "B.SilkS")
			(effects
				(font
					(size 0.7 0.7)
					(thickness 0.15)
				)
				(justify left bottom mirror)
			)
		)
		(property "Value" "C_100n_0402"
			(at 0 -1.169 135)
			(layer "B.Fab")
			(effects
				(font
					(size 0.7 0.7)
					(thickness 0.15)
				)
				(justify left bottom mirror)
			)
		)
		(property "Description" "SMD Multilayer Ceramic Capacitor, 0.1 µF, 50 V, 0402 [1005 Metric], ± 10%, X5R, GRM Series"
			(at 0 0 315)
			(layer "F.Fab")
			(hide yes)
			(effects
				(font
					(size 1.27 1.27)
					(thickness 0.15)
				)
			)
		)
		(property "Author" "Antmicro"
			(at -44.934295 180.719015 0)
			(layer "B.Fab")
			(hide yes)
			(effects
				(font
					(size 1 1)
					(thickness 0.15)
				)
				(justify mirror)
			)
		)
		(property "Dielectric" "X5R"
			(at -44.934295 180.719015 0)
			(layer "B.Fab")
			(hide yes)
			(effects
				(font
					(size 1 1)
					(thickness 0.15)
				)
				(justify mirror)
			)
		)
		(property "License" "Apache-2.0"
			(at -44.934295 180.719015 0)
			(layer "B.Fab")
			(hide yes)
			(effects
				(font
					(size 1 1)
					(thickness 0.15)
				)
				(justify mirror)
			)
		)
		(property "MPN" "GRM155R61H104KE14D"
			(at -44.934295 180.719015 0)
			(layer "B.Fab")
			(hide yes)
			(effects
				(font
					(size 1 1)
					(thickness 0.15)
				)
				(justify mirror)
			)
		)
		(property "Manufacturer" "Murata"
			(at -44.934295 180.719015 0)
			(layer "B.Fab")
			(hide yes)
			(effects
				(font
					(size 1 1)
					(thickness 0.15)
				)
				(justify mirror)
			)
		)
		(property "Val" "100n"
			(at -44.934295 180.719015 0)
			(layer "B.Fab")
			(hide yes)
			(effects
				(font
					(size 1 1)
					(thickness 0.15)
				)
				(justify mirror)
			)
		)
		(property "Voltage" "50V"
			(at -44.934295 180.719015 0)
			(layer "B.Fab")
			(hide yes)
			(effects
				(font
					(size 1 1)
					(thickness 0.15)
				)
				(justify mirror)
			)
		)
		(sheetname "FPGA Bank 33 & 34")
		(sheetfile "fpga-bank-33-34.kicad_sch")
		(attr smd)
		(fp_poly
			(pts
				(xy -0.925 0.47) (xy 0.925 0.47) (xy 0.925 -0.47) (xy -0.925 -0.47)
			)
			(stroke
				(width 0.05)
				(type default)
			)
			(fill no)
			(layer "B.CrtYd")
		)
		(fp_line
			(start -0.494 0.25)
			(end 0.504 0.25)
			(stroke
				(width 0.15)
				(type solid)
			)
			(layer "B.Fab")
		)
		(fp_line
			(start -0.494 -0.248)
			(end -0.494 0.25)
			(stroke
				(width 0.15)
				(type solid)
			)
			(layer "B.Fab")
		)
		(fp_line
			(start 0.504 0.25)
			(end 0.504 -0.248)
			(stroke
				(width 0.15)
				(type solid)
			)
			(layer "B.Fab")
		)
		(fp_line
			(start 0.504 -0.248)
			(end -0.494 -0.248)
			(stroke
				(width 0.15)
				(type solid)
			)
			(layer "B.Fab")
		)
		(pad "1" smd roundrect
			(at -0.48 0 315)
			(size 0.59 0.64)
			(layers "B.Cu" "B.Mask" "B.Paste")
			(roundrect_rratio 0.25)
			(net 1 "GND")
			(pintype "passive")
		)
		(pad "2" smd roundrect
			(at 0.48 0 315)
			(size 0.59 0.64)
			(layers "B.Cu" "B.Mask" "B.Paste")
			(roundrect_rratio 0.25)
			(net 26 "+1V8")
			(pintype "passive")
		)
	)
	(footprint "antmicro-footprints:C_0201"
		(layer "B.Cu")
		(at 191.2 128.2 -45)
		(descr "Capacitor SMD 0201")
		(tags "capacitor SMD 0201")
		(property "Reference" "C66"
			(at -4.030509 -35.532116 315)
			(unlocked yes)
			(layer "B.SilkS")
			(effects
				(font
					(size 0.7 0.7)
					(thickness 0.15)
				)
				(justify left bottom mirror)
			)
		)
		(property "Value" "C_4u7_0201"
			(at 0 -1.399999 135)
			(layer "B.Fab")
			(effects
				(font
					(size 0.7 0.7)
					(thickness 0.15)
				)
				(justify left bottom mirror)
			)
		)
		(property "Description" "SMD Multilayer Ceramic Capacitor, 4.7 µF, 6.3 V, 0201 [0603 Metric], ± 20%, X5R, GRM Series"
			(at 0 0 315)
			(layer "F.Fab")
			(hide yes)
			(effects
				(font
					(size 1.27 1.27)
					(thickness 0.15)
				)
			)
		)
		(property "Author" "Antmicro"
			(at -34.649906 172.747727 0)
			(layer "B.Fab")
			(hide yes)
			(effects
				(font
					(size 1 1)
					(thickness 0.15)
				)
				(justify mirror)
			)
		)
		(property "Dielectric" ""
			(at -34.649906 172.747727 0)
			(layer "B.Fab")
			(hide yes)
			(effects
				(font
					(size 1 1)
					(thickness 0.15)
				)
				(justify mirror)
			)
		)
		(property "License" "Apache-2.0"
			(at -34.649906 172.747727 0)
			(layer "B.Fab")
			(hide yes)
			(effects
				(font
					(size 1 1)
					(thickness 0.15)
				)
				(justify mirror)
			)
		)
		(property "MPN" "GRM035R60J475ME15D"
			(at -34.649906 172.747727 0)
			(layer "B.Fab")
			(hide yes)
			(effects
				(font
					(size 1 1)
					(thickness 0.15)
				)
				(justify mirror)
			)
		)
		(property "Manufacturer" "Murata"
			(at -34.649906 172.747727 0)
			(layer "B.Fab")
			(hide yes)
			(effects
				(font
					(size 1 1)
					(thickness 0.15)
				)
				(justify mirror)
			)
		)
		(property "Val" "4u7"
			(at -34.649906 172.747727 0)
			(layer "B.Fab")
			(hide yes)
			(effects
				(font
					(size 1 1)
					(thickness 0.15)
				)
				(justify mirror)
			)
		)
		(property "Voltage" ""
			(at -34.649906 172.747727 0)
			(layer "B.Fab")
			(hide yes)
			(effects
				(font
					(size 1 1)
					(thickness 0.15)
				)
				(justify mirror)
			)
		)
		(sheetname "FPGA supply")
		(sheetfile "fpga-supply.kicad_sch")
		(attr smd)
		(fp_poly
			(pts
				(xy -0.7 0.35) (xy 0.7 0.35) (xy 0.7 -0.35) (xy -0.7 -0.35)
			)
			(stroke
				(width 0.05)
				(type default)
			)
			(fill no)
			(layer "B.CrtYd")
		)
		(fp_poly
			(pts
				(xy 0.3 -0.15) (xy -0.301 -0.15) (xy -0.301 0.149) (xy 0.3 0.149)
			)
			(stroke
				(width 0.15)
				(type solid)
			)
			(fill no)
			(layer "B.Fab")
		)
		(pad "" smd roundrect
			(at -0.349 0.002 315)
			(size 0.318 0.36)
			(layers "B.Paste")
			(roundrect_rratio 0.25)
		)
		(pad "" smd roundrect
			(at 0.341 0.002 315)
			(size 0.318 0.36)
			(layers "B.Paste")
			(roundrect_rratio 0.25)
		)
		(pad "1" smd roundrect
			(at -0.321 0.002 315)
			(size 0.46 0.4)
			(layers "B.Cu" "B.Mask")
			(roundrect_rratio 0.25)
			(net 1 "GND")
			(pintype "passive")
		)
		(pad "2" smd roundrect
			(at 0.32 0.002 315)
			(size 0.46 0.4)
			(layers "B.Cu" "B.Mask")
			(roundrect_rratio 0.25)
			(net 6 "+1V0_MGTAVCC")
			(pintype "passive")
		)
	)
	(footprint "antmicro-footprints:NetTie-2_SMD_Pad0.127mm"
		(layer "B.Cu")
		(at 208.100001 147.257 90)
		(descr "Net tie, 2 pin, 0.127mm  SMD pads")
		(tags "net tie")
		(property "Reference" "NT31"
			(at -0.128 1.345 270)
			(layer "B.SilkS")
			(hide yes)
			(effects
				(font
					(size 0.7 0.7)
					(thickness 0.15)
				)
				(justify left bottom mirror)
			)
		)
		(property "Value" "Net-Tie_2"
			(at 0 -1.199 270)
			(layer "B.Fab")
			(effects
				(font
					(size 0.7 0.7)
					(thickness 0.15)
				)
				(justify left bottom mirror)
			)
		)
		(property "Description" "Net tie, 2 pins"
			(at 0 0 90)
			(layer "F.Fab")
			(hide yes)
			(effects
				(font
					(size 1.27 1.27)
					(thickness 0.15)
				)
			)
		)
		(property "Author" "Antmicro"
			(at 355.357001 -60.843001 0)
			(layer "B.Fab")
			(hide yes)
			(effects
				(font
					(size 1 1)
					(thickness 0.15)
				)
				(justify mirror)
			)
		)
		(property "License" "Apache-2.0"
			(at 355.357001 -60.843001 0)
			(layer "B.Fab")
			(hide yes)
			(effects
				(font
					(size 1 1)
					(thickness 0.15)
				)
				(justify mirror)
			)
		)
		(property "MPN" ""
			(at 355.357001 -60.843001 0)
			(layer "B.Fab")
			(hide yes)
			(effects
				(font
					(size 1 1)
					(thickness 0.15)
				)
				(justify mirror)
			)
		)
		(property "Manufacturer" ""
			(at 355.357001 -60.843001 0)
			(layer "B.Fab")
			(hide yes)
			(effects
				(font
					(size 1 1)
					(thickness 0.15)
				)
				(justify mirror)
			)
		)
		(sheetname "DC-DC Converters")
		(sheetfile "dc-dc.kicad_sch")
		(attr exclude_from_pos_files)
		(net_tie_pad_groups "1, 2")
		(fp_poly
			(pts
				(xy -0.0635 0.0635) (xy 0.0625 0.0635) (xy 0.0625 -0.0635) (xy -0.0635 -0.0635)
			)
			(stroke
				(width 0)
				(type solid)
			)
			(fill yes)
			(layer "B.Cu")
		)
		(pad "1" smd roundrect
			(at -0.127 0 270)
			(size 0.127 0.127)
			(layers "B.Cu")
			(roundrect_rratio 0.5)
			(chamfer_ratio 0)
			(chamfer top_left bottom_left)
			(net 1219 "/DC-DC Converters/SENSE_3V3_1_P")
			(pinfunction "1")
			(pintype "passive")
		)
		(pad "2" smd roundrect
			(at 0.126 0 90)
			(size 0.127 0.127)
			(layers "B.Cu")
			(roundrect_rratio 0.5)
			(chamfer_ratio 0)
			(chamfer top_left bottom_left)
			(net 24 "+3V3")
			(pinfunction "2")
			(pintype "passive")
		)
	)
	(footprint "antmicro-footprints:C_0402_1005Metric"
		(layer "B.Cu")
		(at 196.75 127.825)
		(descr "Capacitor SMD 0402")
		(tags "capacitor SMD 0402")
		(property "Reference" "C72"
			(at 25.075 -28.75 180)
			(layer "B.SilkS")
			(effects
				(font
					(size 0.7 0.7)
					(thickness 0.15)
				)
				(justify left bottom mirror)
			)
		)
		(property "Value" "C_100n_0402"
			(at 0 -1.169 180)
			(layer "B.Fab")
			(effects
				(font
					(size 0.7 0.7)
					(thickness 0.15)
				)
				(justify left bottom mirror)
			)
		)
		(property "Description" "SMD Multilayer Ceramic Capacitor, 0.1 µF, 50 V, 0402 [1005 Metric], ± 10%, X5R, GRM Series"
			(at 0 0 0)
			(layer "F.Fab")
			(hide yes)
			(effects
				(font
					(size 1.27 1.27)
					(thickness 0.15)
				)
			)
		)
		(property "Author" "Antmicro"
			(at 0 0 0)
			(layer "B.Fab")
			(hide yes)
			(effects
				(font
					(size 1 1)
					(thickness 0.15)
				)
				(justify mirror)
			)
		)
		(property "Dielectric" "X5R"
			(at 0 0 0)
			(layer "B.Fab")
			(hide yes)
			(effects
				(font
					(size 1 1)
					(thickness 0.15)
				)
				(justify mirror)
			)
		)
		(property "License" "Apache-2.0"
			(at 0 0 0)
			(layer "B.Fab")
			(hide yes)
			(effects
				(font
					(size 1 1)
					(thickness 0.15)
				)
				(justify mirror)
			)
		)
		(property "MPN" "GRM155R61H104KE14D"
			(at 0 0 0)
			(layer "B.Fab")
			(hide yes)
			(effects
				(font
					(size 1 1)
					(thickness 0.15)
				)
				(justify mirror)
			)
		)
		(property "Manufacturer" "Murata"
			(at 0 0 0)
			(layer "B.Fab")
			(hide yes)
			(effects
				(font
					(size 1 1)
					(thickness 0.15)
				)
				(justify mirror)
			)
		)
		(property "Val" "100n"
			(at 0 0 0)
			(layer "B.Fab")
			(hide yes)
			(effects
				(font
					(size 1 1)
					(thickness 0.15)
				)
				(justify mirror)
			)
		)
		(property "Voltage" "50V"
			(at 0 0 0)
			(layer "B.Fab")
			(hide yes)
			(effects
				(font
					(size 1 1)
					(thickness 0.15)
				)
				(justify mirror)
			)
		)
		(sheetname "FPGA supply")
		(sheetfile "fpga-supply.kicad_sch")
		(attr smd)
		(fp_rect
			(start -0.925 0.47)
			(end 0.925 -0.47)
			(stroke
				(width 0.05)
				(type default)
			)
			(fill no)
			(layer "B.CrtYd")
		)
		(fp_line
			(start -0.494 -0.248)
			(end -0.494 0.25)
			(stroke
				(width 0.15)
				(type solid)
			)
			(layer "B.Fab")
		)
		(fp_line
			(start -0.494 0.25)
			(end 0.504 0.25)
			(stroke
				(width 0.15)
				(type solid)
			)
			(layer "B.Fab")
		)
		(fp_line
			(start 0.504 -0.248)
			(end -0.494 -0.248)
			(stroke
				(width 0.15)
				(type solid)
			)
			(layer "B.Fab")
		)
		(fp_line
			(start 0.504 0.25)
			(end 0.504 -0.248)
			(stroke
				(width 0.15)
				(type solid)
			)
			(layer "B.Fab")
		)
		(pad "1" smd roundrect
			(at -0.48 0)
			(size 0.59 0.64)
			(layers "B.Cu" "B.Mask" "B.Paste")
			(roundrect_rratio 0.25)
			(net 1 "GND")
			(pintype "passive")
		)
		(pad "2" smd roundrect
			(at 0.48 0)
			(size 0.59 0.64)
			(layers "B.Cu" "B.Mask" "B.Paste")
			(roundrect_rratio 0.25)
			(net 26 "+1V8")
			(pintype "passive")
		)
	)
	(footprint "antmicro-footprints:C_0603_1608Metric"
		(layer "B.Cu")
		(at 200 115.65 -90)
		(descr "Capacitor SMD 0603")
		(tags "capacitor 0603")
		(property "Reference" "C2"
			(at -2.65 -0.375 90)
			(layer "B.SilkS")
			(effects
				(font
					(size 0.7 0.7)
					(thickness 0.15)
				)
				(justify left bottom mirror)
			)
		)
		(property "Value" "C_47u_0603"
			(at 0 -1.6 90)
			(layer "B.Fab")
			(effects
				(font
					(size 0.7 0.7)
					(thickness 0.15)
				)
				(justify left bottom mirror)
			)
		)
		(property "Description" "SMD Multilayer Ceramic Capacitor, 47 µF, 6.3 V, 0603 [1608 Metric], ± 20%, X5R, GRM Series"
			(at 0 0 270)
			(layer "F.Fab")
			(hide yes)
			(effects
				(font
					(size 1.27 1.27)
					(thickness 0.15)
				)
			)
		)
		(property "Author" "Antmicro"
			(at 84.35 315.65 0)
			(layer "B.Fab")
			(hide yes)
			(effects
				(font
					(size 1 1)
					(thickness 0.15)
				)
				(justify mirror)
			)
		)
		(property "Dielectric" ""
			(at 84.35 315.65 0)
			(layer "B.Fab")
			(hide yes)
			(effects
				(font
					(size 1 1)
					(thickness 0.15)
				)
				(justify mirror)
			)
		)
		(property "License" "Apache-2.0"
			(at 84.35 315.65 0)
			(layer "B.Fab")
			(hide yes)
			(effects
				(font
					(size 1 1)
					(thickness 0.15)
				)
				(justify mirror)
			)
		)
		(property "MPN" "GRM188R60J476ME15D"
			(at 84.35 315.65 0)
			(layer "B.Fab")
			(hide yes)
			(effects
				(font
					(size 1 1)
					(thickness 0.15)
				)
				(justify mirror)
			)
		)
		(property "Manufacturer" "Murata"
			(at 84.35 315.65 0)
			(layer "B.Fab")
			(hide yes)
			(effects
				(font
					(size 1 1)
					(thickness 0.15)
				)
				(justify mirror)
			)
		)
		(property "Val" "47u"
			(at 84.35 315.65 0)
			(layer "B.Fab")
			(hide yes)
			(effects
				(font
					(size 1 1)
					(thickness 0.15)
				)
				(justify mirror)
			)
		)
		(property "Voltage" ""
			(at 84.35 315.65 0)
			(layer "B.Fab")
			(hide yes)
			(effects
				(font
					(size 1 1)
					(thickness 0.15)
				)
				(justify mirror)
			)
		)
		(sheetname "FPGA Config")
		(sheetfile "fpga-config.kicad_sch")
		(attr smd)
		(fp_line
			(start -0.15 0.4)
			(end 0.15 0.4)
			(stroke
				(width 0.15)
				(type solid)
			)
			(layer "B.SilkS")
		)
		(fp_line
			(start -0.15 -0.4)
			(end 0.15 -0.4)
			(stroke
				(width 0.15)
				(type solid)
			)
			(layer "B.SilkS")
		)
		(fp_rect
			(start -1.25 0.65)
			(end 1.25 -0.65)
			(stroke
				(width 0.05)
				(type solid)
			)
			(fill no)
			(layer "B.CrtYd")
		)
		(fp_rect
			(start -0.8 0.4)
			(end 0.8 -0.4)
			(stroke
				(width 0.15)
				(type solid)
			)
			(fill no)
			(layer "B.Fab")
		)
		(pad "1" smd roundrect
			(at -0.7 0 270)
			(size 0.8 1)
			(layers "B.Cu" "B.Mask" "B.Paste")
			(roundrect_rratio 0.2)
			(net 1 "GND")
			(pintype "passive")
		)
		(pad "2" smd roundrect
			(at 0.7 0 270)
			(size 0.8 1)
			(layers "B.Cu" "B.Mask" "B.Paste")
			(roundrect_rratio 0.2)
			(net 24 "+3V3")
			(pintype "passive")
		)
	)
	(footprint "antmicro-footprints:C_0402_1005Metric"
		(layer "B.Cu")
		(at 213.5 121.025 -90)
		(descr "Capacitor SMD 0402")
		(tags "capacitor SMD 0402")
		(property "Reference" "C44"
			(at -1.1 -1.3 90)
			(layer "B.SilkS")
			(effects
				(font
					(size 0.7 0.7)
					(thickness 0.15)
				)
				(justify left bottom mirror)
			)
		)
		(property "Value" "C_100n_0402"
			(at 0 -1.169 90)
			(layer "B.Fab")
			(effects
				(font
					(size 0.7 0.7)
					(thickness 0.15)
				)
				(justify left bottom mirror)
			)
		)
		(property "Description" "SMD Multilayer Ceramic Capacitor, 0.1 µF, 50 V, 0402 [1005 Metric], ± 10%, X5R, GRM Series"
			(at 0 0 270)
			(layer "F.Fab")
			(hide yes)
			(effects
				(font
					(size 1.27 1.27)
					(thickness 0.15)
				)
			)
		)
		(property "Author" "Antmicro"
			(at 92.475 334.525 0)
			(layer "B.Fab")
			(hide yes)
			(effects
				(font
					(size 1 1)
					(thickness 0.15)
				)
				(justify mirror)
			)
		)
		(property "Dielectric" "X5R"
			(at 92.475 334.525 0)
			(layer "B.Fab")
			(hide yes)
			(effects
				(font
					(size 1 1)
					(thickness 0.15)
				)
				(justify mirror)
			)
		)
		(property "License" "Apache-2.0"
			(at 92.475 334.525 0)
			(layer "B.Fab")
			(hide yes)
			(effects
				(font
					(size 1 1)
					(thickness 0.15)
				)
				(justify mirror)
			)
		)
		(property "MPN" "GRM155R61H104KE14D"
			(at 92.475 334.525 0)
			(layer "B.Fab")
			(hide yes)
			(effects
				(font
					(size 1 1)
					(thickness 0.15)
				)
				(justify mirror)
			)
		)
		(property "Manufacturer" "Murata"
			(at 92.475 334.525 0)
			(layer "B.Fab")
			(hide yes)
			(effects
				(font
					(size 1 1)
					(thickness 0.15)
				)
				(justify mirror)
			)
		)
		(property "Val" "100n"
			(at 92.475 334.525 0)
			(layer "B.Fab")
			(hide yes)
			(effects
				(font
					(size 1 1)
					(thickness 0.15)
				)
				(justify mirror)
			)
		)
		(property "Voltage" "50V"
			(at 92.475 334.525 0)
			(layer "B.Fab")
			(hide yes)
			(effects
				(font
					(size 1 1)
					(thickness 0.15)
				)
				(justify mirror)
			)
		)
		(sheetname "FPGA Bank 16 & 17")
		(sheetfile "fpga-bank-16-17.kicad_sch")
		(attr smd)
		(fp_rect
			(start -0.925 0.47)
			(end 0.925 -0.47)
			(stroke
				(width 0.05)
				(type default)
			)
			(fill no)
			(layer "B.CrtYd")
		)
		(fp_line
			(start -0.494 0.25)
			(end 0.504 0.25)
			(stroke
				(width 0.15)
				(type solid)
			)
			(layer "B.Fab")
		)
		(fp_line
			(start 0.504 0.25)
			(end 0.504 -0.248)
			(stroke
				(width 0.15)
				(type solid)
			)
			(layer "B.Fab")
		)
		(fp_line
			(start -0.494 -0.248)
			(end -0.494 0.25)
			(stroke
				(width 0.15)
				(type solid)
			)
			(layer "B.Fab")
		)
		(fp_line
			(start 0.504 -0.248)
			(end -0.494 -0.248)
			(stroke
				(width 0.15)
				(type solid)
			)
			(layer "B.Fab")
		)
		(pad "1" smd roundrect
			(at -0.48 0 270)
			(size 0.59 0.64)
			(layers "B.Cu" "B.Mask" "B.Paste")
			(roundrect_rratio 0.25)
			(net 1 "GND")
			(pintype "passive")
		)
		(pad "2" smd roundrect
			(at 0.48 0 270)
			(size 0.59 0.64)
			(layers "B.Cu" "B.Mask" "B.Paste")
			(roundrect_rratio 0.25)
			(net 3 "VCC_USR_B")
			(pintype "passive")
		)
	)
)
